# S9S_MB_2U (Grand Teton) — schematic netlist excerpt (pin names and nets, part order shuffled) for the footprints in the layout excerpt that follows; sources: Cadence DE-HDL packaged netlist, KiCad conversion of 03242023_DA0F0TMBIJ0_F0T_Motherboard_J_brd_V01_OCP.brd

PC2150  Q_CAP  3900PF 50V 10% EMPTY  pkg C0402  page 162 : A = P12V_OCP_GATE_2 ; B = GND
PC1655  Q_CAP  100NF 50V 10% X7R  pkg C0402  page 275 : A = P12V_AUX ; B = GND

(kicad_pcb
	(version 20260206)
	(generator "pcbnew")
	(generator_version "10.0")
	(general
		(thickness 1.6)
		(legacy_teardrops no)
	)
	(paper "A4")
	(title_block
		(title "03242023_DA0F0TMBIJ0_F0T_Motherboard_J_brd_V01_OCP.brd")
		(comment 1 "Grand Teton / footprints 2248-2249 of 6105")
	)
	(layers
		(0 "F.Cu" signal "TOP")
		(4 "In1.Cu" signal "GND")
		(6 "In2.Cu" signal "IN1")
		(8 "In3.Cu" signal "GND1")
		(10 "In4.Cu" signal "IN2")
		(12 "In5.Cu" signal "GND2")
		(14 "In6.Cu" signal "IN3")
		(16 "In7.Cu" signal "GND3")
		(18 "In8.Cu" signal "VCC")
		(20 "In9.Cu" signal "VCC1")
		(22 "In10.Cu" signal "GND4")
		(24 "In11.Cu" signal "IN4")
		(26 "In12.Cu" signal "GND5")
		(28 "In13.Cu" signal "IN5")
		(30 "In14.Cu" signal "GND6")
		(32 "In15.Cu" signal "IN6")
		(34 "In16.Cu" signal "GND7")
		(2 "B.Cu" signal "BOTTOM")
		(9 "F.Adhes" user "F.Adhesive")
		(11 "B.Adhes" user "B.Adhesive")
		(13 "F.Paste" user "Package Geometry/Pastemask Top")
		(15 "B.Paste" user "Package Geometry/Pastemask Bottom")
		(5 "F.SilkS" user "Ref Des/Silkscreen Top")
		(7 "B.SilkS" user "Ref Des/Silkscreen Bottom")
		(1 "F.Mask" user "Board Geometry/Soldermask Top")
		(3 "B.Mask" user "Board Geometry/Soldermask Bottom")
		(17 "Dwgs.User" user "User.Drawings")
		(19 "Cmts.User" user "User.Comments")
		(21 "Eco1.User" user "User.Eco1")
		(23 "Eco2.User" user "User.Eco2")
		(25 "Edge.Cuts" user "Board Geometry/Outline")
		(27 "Margin" user)
		(31 "F.CrtYd" user "Package Geometry/Place Bound Top")
		(29 "B.CrtYd" user "Package Geometry/Place Bound Bottom")
		(35 "F.Fab" user "Ref Des/Assembly Top")
		(33 "B.Fab" user "Ref Des/Assembly Bottom")
	)
	(footprint ""
		(layer "F.Cu")
		(at 80.913478 -23.317962)
		(property "Reference" "PC2150"
			(at 0 0 0)
			(layer "F.SilkS")
			(hide yes)
			(effects
				(font
					(size 1.27 1.27)
				)
			)
		)
		(property "Value" ""
			(at 0 0 0)
			(layer "F.Fab")
			(effects
				(font
					(size 1.27 1.27)
				)
			)
		)
		(duplicate_pad_numbers_are_jumpers no)
		(fp_line
			(start -0.7874 -0.4064)
			(end 0.7874 -0.4064)
			(stroke
				(width 0.1524)
				(type default)
			)
			(layer "F.SilkS")
		)
		(fp_line
			(start -0.7874 0.4064)
			(end -0.7874 -0.4064)
			(stroke
				(width 0.1524)
				(type default)
			)
			(layer "F.SilkS")
		)
		(fp_line
			(start 0.7874 -0.4064)
			(end 0.7874 0.4064)
			(stroke
				(width 0.1524)
				(type default)
			)
			(layer "F.SilkS")
		)
		(fp_line
			(start 0.7874 0.4064)
			(end -0.7874 0.4064)
			(stroke
				(width 0.1524)
				(type default)
			)
			(layer "F.SilkS")
		)
		(fp_line
			(start -0.67945 -0.305054)
			(end -0.12065 -0.305054)
			(stroke
				(width 0.1)
				(type default)
			)
			(layer "F.Fab")
		)
		(fp_line
			(start -0.67945 0.3048)
			(end -0.67945 -0.305054)
			(stroke
				(width 0.1)
				(type default)
			)
			(layer "F.Fab")
		)
		(fp_line
			(start -0.12065 -0.305054)
			(end -0.12065 -0.2794)
			(stroke
				(width 0.1)
				(type default)
			)
			(layer "F.Fab")
		)
		(fp_line
			(start -0.12065 -0.2794)
			(end 0.12065 -0.2794)
			(stroke
				(width 0.1)
				(type default)
			)
			(layer "F.Fab")
		)
		(fp_line
			(start -0.12065 0.2794)
			(end -0.12065 0.3048)
			(stroke
				(width 0.1)
				(type default)
			)
			(layer "F.Fab")
		)
		(fp_line
			(start -0.12065 0.3048)
			(end -0.67945 0.3048)
			(stroke
				(width 0.1)
				(type default)
			)
			(layer "F.Fab")
		)
		(fp_line
			(start 0.120396 0.2794)
			(end -0.12065 0.2794)
			(stroke
				(width 0.1)
				(type default)
			)
			(layer "F.Fab")
		)
		(fp_line
			(start 0.120396 0.3048)
			(end 0.120396 0.2794)
			(stroke
				(width 0.1)
				(type default)
			)
			(layer "F.Fab")
		)
		(fp_line
			(start 0.12065 -0.3048)
			(end 0.67945 -0.3048)
			(stroke
				(width 0.1)
				(type default)
			)
			(layer "F.Fab")
		)
		(fp_line
			(start 0.12065 -0.2794)
			(end 0.12065 -0.3048)
			(stroke
				(width 0.1)
				(type default)
			)
			(layer "F.Fab")
		)
		(fp_line
			(start 0.67945 -0.3048)
			(end 0.67945 0.3048)
			(stroke
				(width 0.1)
				(type default)
			)
			(layer "F.Fab")
		)
		(fp_line
			(start 0.67945 0.3048)
			(end 0.120396 0.3048)
			(stroke
				(width 0.1)
				(type default)
			)
			(layer "F.Fab")
		)
		(pad "1" smd circle
			(at -0.40005 0)
			(size 0 0)
			(layers "F.Cu" "F.Mask" "F.Paste")
			(net "P12V_OCP_GATE_2")
		)
		(pad "2" smd circle
			(at 0.40005 0)
			(size 0 0)
			(layers "F.Cu" "F.Mask" "F.Paste")
			(net "GND")
		)
	)
	(footprint ""
		(layer "F.Cu")
		(at 433.076858 -166.405814)
		(property "Reference" "PC1655"
			(at 0 0 0)
			(layer "F.SilkS")
			(hide yes)
			(effects
				(font
					(size 1.27 1.27)
				)
			)
		)
		(property "Value" ""
			(at 0 0 0)
			(layer "F.Fab")
			(effects
				(font
					(size 1.27 1.27)
				)
			)
		)
		(duplicate_pad_numbers_are_jumpers no)
		(fp_line
			(start -0.7874 -0.4064)
			(end 0.7874 -0.4064)
			(stroke
				(width 0.1524)
				(type default)
			)
			(layer "F.SilkS")
		)
		(fp_line
			(start -0.7874 0.4064)
			(end -0.7874 -0.4064)
			(stroke
				(width 0.1524)
				(type default)
			)
			(layer "F.SilkS")
		)
		(fp_line
			(start 0.7874 -0.4064)
			(end 0.7874 0.4064)
			(stroke
				(width 0.1524)
				(type default)
			)
			(layer "F.SilkS")
		)
		(fp_line
			(start 0.7874 0.4064)
			(end -0.7874 0.4064)
			(stroke
				(width 0.1524)
				(type default)
			)
			(layer "F.SilkS")
		)
		(fp_line
			(start -0.67945 -0.305054)
			(end -0.12065 -0.305054)
			(stroke
				(width 0.1)
				(type default)
			)
			(layer "F.Fab")
		)
		(fp_line
			(start -0.67945 0.3048)
			(end -0.67945 -0.305054)
			(stroke
				(width 0.1)
				(type default)
			)
			(layer "F.Fab")
		)
		(fp_line
			(start -0.12065 -0.305054)
			(end -0.12065 -0.2794)
			(stroke
				(width 0.1)
				(type default)
			)
			(layer "F.Fab")
		)
		(fp_line
			(start -0.12065 -0.2794)
			(end 0.12065 -0.2794)
			(stroke
				(width 0.1)
				(type default)
			)
			(layer "F.Fab")
		)
		(fp_line
			(start -0.12065 0.2794)
			(end -0.12065 0.3048)
			(stroke
				(width 0.1)
				(type default)
			)
			(layer "F.Fab")
		)
		(fp_line
			(start -0.12065 0.3048)
			(end -0.67945 0.3048)
			(stroke
				(width 0.1)
				(type default)
			)
			(layer "F.Fab")
		)
		(fp_line
			(start 0.120396 0.2794)
			(end -0.12065 0.2794)
			(stroke
				(width 0.1)
				(type default)
			)
			(layer "F.Fab")
		)
		(fp_line
			(start 0.120396 0.3048)
			(end 0.120396 0.2794)
			(stroke
				(width 0.1)
				(type default)
			)
			(layer "F.Fab")
		)
		(fp_line
			(start 0.12065 -0.3048)
			(end 0.67945 -0.3048)
			(stroke
				(width 0.1)
				(type default)
			)
			(layer "F.Fab")
		)
		(fp_line
			(start 0.12065 -0.2794)
			(end 0.12065 -0.3048)
			(stroke
				(width 0.1)
				(type default)
			)
			(layer "F.Fab")
		)
		(fp_line
			(start 0.67945 -0.3048)
			(end 0.67945 0.3048)
			(stroke
				(width 0.1)
				(type default)
			)
			(layer "F.Fab")
		)
		(fp_line
			(start 0.67945 0.3048)
			(end 0.120396 0.3048)
			(stroke
				(width 0.1)
				(type default)
			)
			(layer "F.Fab")
		)
		(pad "1" smd circle
			(at -0.40005 0)
			(size 0 0)
			(layers "F.Cu" "F.Mask" "F.Paste")
			(net "P12V_AUX")
		)
		(pad "2" smd circle
			(at 0.40005 0)
			(size 0 0)
			(layers "F.Cu" "F.Mask" "F.Paste")
			(net "GND")
		)
	)
)
